# TIMECARD (Time Appliance Project (Time Card)) — schematic netlist excerpt (pin names and nets, part order shuffled) for the footprints in the layout excerpt that follows; sources: Cadence DE-HDL packaged netlist, KiCad conversion of R4006-B0001-02_R01.brd

ME9  MEC_MTH8  pkg MTH125C236N_V8  page 34
  \1\  = SG
  \2\  = SG
  \3\  = SG
  \4\  = SG
  \5\  = SG
  \6\  = SG
  \7\  = SG
  \8\  = SG

(kicad_pcb
	(version 20260206)
	(generator "pcbnew")
	(generator_version "10.0")
	(general
		(thickness 1.6)
		(legacy_teardrops no)
	)
	(paper "A4")
	(title_block
		(title "timecard-production-celestica-r4006 — R4006-B0001-02_R01.brd")
		(comment 1 "Time Appliance Project (Time Card) / footprints 256-256 of 1113")
	)
	(layers
		(0 "F.Cu" signal "TOP")
		(4 "In1.Cu" signal "L02_GND1")
		(6 "In2.Cu" signal "L03_SIG1")
		(8 "In3.Cu" signal "L04_GND2")
		(10 "In4.Cu" signal "L05_VCC1")
		(12 "In5.Cu" signal "L06_VCC2")
		(14 "In6.Cu" signal "L07_GND3")
		(16 "In7.Cu" signal "L08_SIG2")
		(18 "In8.Cu" signal "L09_GND4")
		(2 "B.Cu" signal "BOTTOM")
		(9 "F.Adhes" user "F.Adhesive")
		(11 "B.Adhes" user "B.Adhesive")
		(13 "F.Paste" user "Package Geometry/Pastemask Top")
		(15 "B.Paste" user "Package Geometry/Pastemask Bottom")
		(5 "F.SilkS" user "Ref Des/Silkscreen Top")
		(7 "B.SilkS" user "Ref Des/Silkscreen Bottom")
		(1 "F.Mask" user "Board Geometry/Soldermask Top")
		(3 "B.Mask" user "Board Geometry/Soldermask Bottom")
		(17 "Dwgs.User" user "User.Drawings")
		(19 "Cmts.User" user "User.Comments")
		(21 "Eco1.User" user "User.Eco1")
		(23 "Eco2.User" user "User.Eco2")
		(25 "Edge.Cuts" user "Board Geometry/Outline")
		(27 "Margin" user)
		(31 "F.CrtYd" user "Package Geometry/Place Bound Top")
		(29 "B.CrtYd" user "Package Geometry/Place Bound Bottom")
		(35 "F.Fab" user "Ref Des/Assembly Top")
		(33 "B.Fab" user "Ref Des/Assembly Bottom")
	)
	(footprint ""
		(layer "F.Cu")
		(at 7.500112 -94.749874)
		(property "Reference" "ME9"
			(at 0.127508 -4.024376 0)
			(unlocked yes)
			(layer "F.SilkS")
			(effects
				(font
					(size 0.7874 0.5842)
					(thickness 0.1524)
				)
			)
		)
		(property "Value" ""
			(at 0 0 0)
			(layer "F.Fab")
			(effects
				(font
					(size 1.27 1.27)
				)
			)
		)
		(property "Device Type" "MEC_MTH8-MTH125C236N_V8-MTH125A"
			(at 0 5.08127 0)
			(unlocked yes)
			(layer "F.Fab")
			(hide yes)
			(effects
				(font
					(size 0.7874 0.5842)
					(thickness 0.1524)
				)
			)
		)
		(duplicate_pad_numbers_are_jumpers no)
		(fp_poly
			(pts
				(arc
					(start 3.5052 0)
					(mid -3.5052 0)
					(end 3.5052 0)
				)
			)
			(stroke
				(width 0)
				(type default)
			)
			(fill no)
			(layer "B.CrtYd")
		)
		(fp_poly
			(pts
				(arc
					(start 3.5052 0)
					(mid -3.5052 0)
					(end 3.5052 0)
				)
			)
			(stroke
				(width 0)
				(type default)
			)
			(fill no)
			(layer "F.CrtYd")
		)
		(fp_circle
			(center 0 0)
			(end 2.9972 0)
			(stroke
				(width 0.1)
				(type default)
			)
			(fill no)
			(layer "B.Fab")
		)
		(fp_circle
			(center 0 0)
			(end 2.9972 0)
			(stroke
				(width 0.1)
				(type default)
			)
			(fill no)
			(layer "F.Fab")
		)
		(pad "" np_thru_hole circle
			(at 0 0)
			(size 2.921 2.921)
			(drill 3.175)
			(layers "*.Cu" "*.Mask")
			(padstack
				(mode front_inner_back)
				(layer "Inner"
					(shape circle)
					(size 2.921 2.921)
					(clearance 0.4445)
				)
				(layer "B.Cu"
					(shape circle)
					(size 2.921 2.921)
				)
			)
		)
		(pad "1" thru_hole circle
			(at 0 -2.4511)
			(size 0.6096 0.6096)
			(drill 0.3048)
			(layers "*.Cu" "*.Mask")
			(remove_unused_layers no)
			(net "SG")
			(padstack
				(mode front_inner_back)
				(layer "Inner"
					(shape circle)
					(size 0.6096 0.6096)
					(clearance 0.1143)
				)
				(layer "B.Cu"
					(shape circle)
					(size 0.6096 0.6096)
				)
			)
		)
		(pad "2" thru_hole circle
			(at 1.733296 -1.733296)
			(size 0.6096 0.6096)
			(drill 0.3048)
			(layers "*.Cu" "*.Mask")
			(remove_unused_layers no)
			(net "SG")
			(padstack
				(mode front_inner_back)
				(layer "Inner"
					(shape circle)
					(size 0.6096 0.6096)
					(clearance 0.1143)
				)
				(layer "B.Cu"
					(shape circle)
					(size 0.6096 0.6096)
				)
			)
		)
		(pad "3" thru_hole circle
			(at 2.4511 0)
			(size 0.6096 0.6096)
			(drill 0.3048)
			(layers "*.Cu" "*.Mask")
			(remove_unused_layers no)
			(net "SG")
			(padstack
				(mode front_inner_back)
				(layer "Inner"
					(shape circle)
					(size 0.6096 0.6096)
					(clearance 0.1143)
				)
				(layer "B.Cu"
					(shape circle)
					(size 0.6096 0.6096)
				)
			)
		)
		(pad "4" thru_hole circle
			(at 1.733296 1.733296)
			(size 0.6096 0.6096)
			(drill 0.3048)
			(layers "*.Cu" "*.Mask")
			(remove_unused_layers no)
			(net "SG")
			(padstack
				(mode front_inner_back)
				(layer "Inner"
					(shape circle)
					(size 0.6096 0.6096)
					(clearance 0.1143)
				)
				(layer "B.Cu"
					(shape circle)
					(size 0.6096 0.6096)
				)
			)
		)
		(pad "5" thru_hole circle
			(at 0 2.4511)
			(size 0.6096 0.6096)
			(drill 0.3048)
			(layers "*.Cu" "*.Mask")
			(remove_unused_layers no)
			(net "SG")
			(padstack
				(mode front_inner_back)
				(layer "Inner"
					(shape circle)
					(size 0.6096 0.6096)
					(clearance 0.1143)
				)
				(layer "B.Cu"
					(shape circle)
					(size 0.6096 0.6096)
				)
			)
		)
		(pad "6" thru_hole circle
			(at -1.733296 1.733296)
			(size 0.6096 0.6096)
			(drill 0.3048)
			(layers "*.Cu" "*.Mask")
			(remove_unused_layers no)
			(net "SG")
			(padstack
				(mode front_inner_back)
				(layer "Inner"
					(shape circle)
					(size 0.6096 0.6096)
					(clearance 0.1143)
				)
				(layer "B.Cu"
					(shape circle)
					(size 0.6096 0.6096)
				)
			)
		)
		(pad "7" thru_hole circle
			(at -2.4511 0)
			(size 0.6096 0.6096)
			(drill 0.3048)
			(layers "*.Cu" "*.Mask")
			(remove_unused_layers no)
			(net "SG")
			(padstack
				(mode front_inner_back)
				(layer "Inner"
					(shape circle)
					(size 0.6096 0.6096)
					(clearance 0.1143)
				)
				(layer "B.Cu"
					(shape circle)
					(size 0.6096 0.6096)
				)
			)
		)
		(pad "8" thru_hole circle
			(at -1.733296 -1.733296)
			(size 0.6096 0.6096)
			(drill 0.3048)
			(layers "*.Cu" "*.Mask")
			(remove_unused_layers no)
			(net "SG")
			(padstack
				(mode front_inner_back)
				(layer "Inner"
					(shape circle)
					(size 0.6096 0.6096)
					(clearance 0.1143)
				)
				(layer "B.Cu"
					(shape circle)
					(size 0.6096 0.6096)
				)
			)
		)
		(zone
			(layers "F.Cu" "B.Cu" "In1.Cu" "In2.Cu" "In3.Cu" "In4.Cu" "In5.Cu" "In6.Cu"
				"In7.Cu" "In8.Cu"
			)
			(hatch none 0.5)
			(connect_pads
				(clearance 0)
			)
			(min_thickness 0.25)
			(keepout
				(tracks not_allowed)
				(vias allowed)
				(pads allowed)
				(copperpour not_allowed)
				(footprints allowed)
			)
			(placement
				(enabled no)
				(sheetname "")
			)
			(fill
				(thermal_gap 0.5)
				(thermal_bridge_width 0.5)
				(island_removal_mode 0)
			)
			(polygon
				(pts
					(arc
						(start 9.392412 -94.749874)
						(mid 5.607812 -94.749874)
						(end 9.392412 -94.749874)
					)
				)
			)
		)
	)
)
